(kicad_pcb
	(version 20260206)
	(generator "pcbnew")
	(generator_version "10.0")
	(general
		(thickness 1.6)
		(legacy_teardrops no)
	)
	(paper "A4")
	(title_block
		(title "04192023_DAF0TMB3IC0_F0TG_MB_C_brd_V02_OCP.brd")
		(comment 1 "Grand Teton / footprints 2101-2107 of 8354")
	)
	(layers
		(0 "F.Cu" signal "TOP")
		(4 "In1.Cu" signal "GND")
		(6 "In2.Cu" signal "IN1")
		(8 "In3.Cu" signal "GND1")
		(10 "In4.Cu" signal "IN2")
		(12 "In5.Cu" signal "GND2")
		(14 "In6.Cu" signal "IN3")
		(16 "In7.Cu" signal "GND3")
		(18 "In8.Cu" signal "VCC")
		(20 "In9.Cu" signal "VCC1")
		(22 "In10.Cu" signal "GND4")
		(24 "In11.Cu" signal "IN4")
		(26 "In12.Cu" signal "GND5")
		(28 "In13.Cu" signal "IN5")
		(30 "In14.Cu" signal "GND6")
		(32 "In15.Cu" signal "IN6")
		(34 "In16.Cu" signal "GND7")
		(2 "B.Cu" signal "BOTTOM")
		(9 "F.Adhes" user "F.Adhesive")
		(11 "B.Adhes" user "B.Adhesive")
		(13 "F.Paste" user "Package Geometry/Pastemask Top")
		(15 "B.Paste" user "Package Geometry/Pastemask Bottom")
		(5 "F.SilkS" user "Ref Des/Silkscreen Top")
		(7 "B.SilkS" user "Ref Des/Silkscreen Bottom")
		(1 "F.Mask" user "Board Geometry/Soldermask Top")
		(3 "B.Mask" user "Board Geometry/Soldermask Bottom")
		(17 "Dwgs.User" user "User.Drawings")
		(19 "Cmts.User" user "User.Comments")
		(21 "Eco1.User" user "User.Eco1")
		(23 "Eco2.User" user "User.Eco2")
		(25 "Edge.Cuts" user "Board Geometry/Outline")
		(27 "Margin" user)
		(31 "F.CrtYd" user "Package Geometry/Place Bound Top")
		(29 "B.CrtYd" user "Package Geometry/Place Bound Bottom")
		(35 "F.Fab" user "Ref Des/Assembly Top")
		(33 "B.Fab" user "Ref Des/Assembly Bottom")
	)
	(footprint ""
		(layer "F.Cu")
		(at 304.419 -367.665)
		(property "Reference" "R8072"
			(at 0 0 0)
			(layer "F.SilkS")
			(hide yes)
			(effects
				(font
					(size 1.27 1.27)
				)
			)
		)
		(property "Value" ""
			(at 0 0 0)
			(layer "F.Fab")
			(effects
				(font
					(size 1.27 1.27)
				)
			)
		)
		(duplicate_pad_numbers_are_jumpers no)
		(fp_line
			(start -0.7874 -0.4064)
			(end 0.7874 -0.4064)
			(stroke
				(width 0.1524)
				(type default)
			)
			(layer "F.SilkS")
		)
		(fp_line
			(start -0.7874 0.4064)
			(end -0.7874 -0.4064)
			(stroke
				(width 0.1524)
				(type default)
			)
			(layer "F.SilkS")
		)
		(fp_line
			(start 0.7874 -0.4064)
			(end 0.7874 0.4064)
			(stroke
				(width 0.1524)
				(type default)
			)
			(layer "F.SilkS")
		)
		(fp_line
			(start 0.7874 0.4064)
			(end -0.7874 0.4064)
			(stroke
				(width 0.1524)
				(type default)
			)
			(layer "F.SilkS")
		)
		(fp_line
			(start -0.67945 -0.305054)
			(end -0.12065 -0.305054)
			(stroke
				(width 0.1)
				(type default)
			)
			(layer "F.Fab")
		)
		(fp_line
			(start -0.67945 0.3048)
			(end -0.67945 -0.305054)
			(stroke
				(width 0.1)
				(type default)
			)
			(layer "F.Fab")
		)
		(fp_line
			(start -0.12065 -0.305054)
			(end -0.12065 -0.2794)
			(stroke
				(width 0.1)
				(type default)
			)
			(layer "F.Fab")
		)
		(fp_line
			(start -0.12065 -0.2794)
			(end 0.12065 -0.2794)
			(stroke
				(width 0.1)
				(type default)
			)
			(layer "F.Fab")
		)
		(fp_line
			(start -0.12065 0.2794)
			(end -0.12065 0.3048)
			(stroke
				(width 0.1)
				(type default)
			)
			(layer "F.Fab")
		)
		(fp_line
			(start -0.12065 0.3048)
			(end -0.67945 0.3048)
			(stroke
				(width 0.1)
				(type default)
			)
			(layer "F.Fab")
		)
		(fp_line
			(start 0.120396 0.2794)
			(end -0.12065 0.2794)
			(stroke
				(width 0.1)
				(type default)
			)
			(layer "F.Fab")
		)
		(fp_line
			(start 0.120396 0.3048)
			(end 0.120396 0.2794)
			(stroke
				(width 0.1)
				(type default)
			)
			(layer "F.Fab")
		)
		(fp_line
			(start 0.12065 -0.3048)
			(end 0.67945 -0.3048)
			(stroke
				(width 0.1)
				(type default)
			)
			(layer "F.Fab")
		)
		(fp_line
			(start 0.12065 -0.2794)
			(end 0.12065 -0.3048)
			(stroke
				(width 0.1)
				(type default)
			)
			(layer "F.Fab")
		)
		(fp_line
			(start 0.67945 -0.3048)
			(end 0.67945 0.3048)
			(stroke
				(width 0.1)
				(type default)
			)
			(layer "F.Fab")
		)
		(fp_line
			(start 0.67945 0.3048)
			(end 0.120396 0.3048)
			(stroke
				(width 0.1)
				(type default)
			)
			(layer "F.Fab")
		)
		(pad "1" smd circle
			(at -0.40005 0)
			(size 0 0)
			(layers "F.Cu" "F.Mask" "F.Paste")
			(net "SMB_SCM_2_R5_SDA")
		)
		(pad "2" smd circle
			(at 0.40005 0)
			(size 0 0)
			(layers "F.Cu" "F.Mask" "F.Paste")
			(net "SMB_DIO_PVDDCR_CPU1_P0_R")
		)
	)
	(footprint ""
		(layer "F.Cu")
		(at 110.152942 -21.7678 -90)
		(property "Reference" "R6271"
			(at 0 0 270)
			(layer "F.SilkS")
			(hide yes)
			(effects
				(font
					(size 1.27 1.27)
				)
			)
		)
		(property "Value" ""
			(at 0 0 270)
			(layer "F.Fab")
			(effects
				(font
					(size 1.27 1.27)
				)
			)
		)
		(duplicate_pad_numbers_are_jumpers no)
		(fp_line
			(start -0.7874 0.4064)
			(end -0.7874 -0.4064)
			(stroke
				(width 0.1524)
				(type default)
			)
			(layer "F.SilkS")
		)
		(fp_line
			(start 0.7874 0.4064)
			(end -0.7874 0.4064)
			(stroke
				(width 0.1524)
				(type default)
			)
			(layer "F.SilkS")
		)
		(fp_line
			(start -0.7874 -0.4064)
			(end 0.7874 -0.4064)
			(stroke
				(width 0.1524)
				(type default)
			)
			(layer "F.SilkS")
		)
		(fp_line
			(start 0.7874 -0.4064)
			(end 0.7874 0.4064)
			(stroke
				(width 0.1524)
				(type default)
			)
			(layer "F.SilkS")
		)
		(fp_line
			(start -0.67945 0.3048)
			(end -0.67945 -0.305054)
			(stroke
				(width 0.1)
				(type default)
			)
			(layer "F.Fab")
		)
		(fp_line
			(start -0.12065 0.3048)
			(end -0.67945 0.3048)
			(stroke
				(width 0.1)
				(type default)
			)
			(layer "F.Fab")
		)
		(fp_line
			(start 0.120396 0.3048)
			(end 0.120396 0.2794)
			(stroke
				(width 0.1)
				(type default)
			)
			(layer "F.Fab")
		)
		(fp_line
			(start 0.67945 0.3048)
			(end 0.120396 0.3048)
			(stroke
				(width 0.1)
				(type default)
			)
			(layer "F.Fab")
		)
		(fp_line
			(start -0.12065 0.2794)
			(end -0.12065 0.3048)
			(stroke
				(width 0.1)
				(type default)
			)
			(layer "F.Fab")
		)
		(fp_line
			(start 0.120396 0.2794)
			(end -0.12065 0.2794)
			(stroke
				(width 0.1)
				(type default)
			)
			(layer "F.Fab")
		)
		(fp_line
			(start -0.12065 -0.2794)
			(end 0.12065 -0.2794)
			(stroke
				(width 0.1)
				(type default)
			)
			(layer "F.Fab")
		)
		(fp_line
			(start 0.12065 -0.2794)
			(end 0.12065 -0.3048)
			(stroke
				(width 0.1)
				(type default)
			)
			(layer "F.Fab")
		)
		(fp_line
			(start 0.12065 -0.3048)
			(end 0.67945 -0.3048)
			(stroke
				(width 0.1)
				(type default)
			)
			(layer "F.Fab")
		)
		(fp_line
			(start 0.67945 -0.3048)
			(end 0.67945 0.3048)
			(stroke
				(width 0.1)
				(type default)
			)
			(layer "F.Fab")
		)
		(fp_line
			(start -0.67945 -0.305054)
			(end -0.12065 -0.305054)
			(stroke
				(width 0.1)
				(type default)
			)
			(layer "F.Fab")
		)
		(fp_line
			(start -0.12065 -0.305054)
			(end -0.12065 -0.2794)
			(stroke
				(width 0.1)
				(type default)
			)
			(layer "F.Fab")
		)
		(pad "1" smd circle
			(at -0.40005 0 270)
			(size 0 0)
			(layers "F.Cu" "F.Mask" "F.Paste")
			(net "USB_HUB2_TI_USB_DP_DN1_MRP_CFG_STRAP")
		)
		(pad "2" smd circle
			(at 0.40005 0 270)
			(size 0 0)
			(layers "F.Cu" "F.Mask" "F.Paste")
			(net "USB_HUB2_MRP_CFG_STRAP")
		)
	)
	(footprint ""
		(layer "F.Cu")
		(at 115.195096 -375.49963 -90)
		(property "Reference" "C1539"
			(at 0 0 270)
			(layer "F.SilkS")
			(hide yes)
			(effects
				(font
					(size 1.27 1.27)
				)
			)
		)
		(property "Value" ""
			(at 0 0 270)
			(layer "F.Fab")
			(effects
				(font
					(size 1.27 1.27)
				)
			)
		)
		(duplicate_pad_numbers_are_jumpers no)
		(fp_line
			(start -0.299974 0.150114)
			(end -0.299974 -0.150114)
			(stroke
				(width 0.1)
				(type default)
			)
			(layer "F.Fab")
		)
		(fp_line
			(start 0.299974 0.150114)
			(end -0.299974 0.150114)
			(stroke
				(width 0.1)
				(type default)
			)
			(layer "F.Fab")
		)
		(fp_line
			(start -0.299974 -0.150114)
			(end 0.299974 -0.150114)
			(stroke
				(width 0.1)
				(type default)
			)
			(layer "F.Fab")
		)
		(fp_line
			(start 0.299974 -0.150114)
			(end 0.299974 0.150114)
			(stroke
				(width 0.1)
				(type default)
			)
			(layer "F.Fab")
		)
		(pad "1" smd rect
			(at -0.2667 0 270)
			(size 0.3048 0.381)
			(layers "F.Cu" "F.Mask" "F.Paste")
			(net "P5E_CPU1_P3_TX_C_DP<4>")
		)
		(pad "2" smd rect
			(at 0.2667 0 270)
			(size 0.3048 0.381)
			(layers "F.Cu" "F.Mask" "F.Paste")
			(net "P5E_CPU1_P3_TX_DP<4>")
		)
	)
	(footprint ""
		(layer "F.Cu")
		(at 200.035668 -78.42377 180)
		(property "Reference" "R73"
			(at 0 0 180)
			(layer "F.SilkS")
			(hide yes)
			(effects
				(font
					(size 1.27 1.27)
				)
			)
		)
		(property "Value" ""
			(at 0 0 180)
			(layer "F.Fab")
			(effects
				(font
					(size 1.27 1.27)
				)
			)
		)
		(duplicate_pad_numbers_are_jumpers no)
		(fp_line
			(start 0.7874 0.4064)
			(end -0.7874 0.4064)
			(stroke
				(width 0.1524)
				(type default)
			)
			(layer "F.SilkS")
		)
		(fp_line
			(start 0.7874 -0.4064)
			(end 0.7874 0.4064)
			(stroke
				(width 0.1524)
				(type default)
			)
			(layer "F.SilkS")
		)
		(fp_line
			(start -0.7874 0.4064)
			(end -0.7874 -0.4064)
			(stroke
				(width 0.1524)
				(type default)
			)
			(layer "F.SilkS")
		)
		(fp_line
			(start -0.7874 -0.4064)
			(end 0.7874 -0.4064)
			(stroke
				(width 0.1524)
				(type default)
			)
			(layer "F.SilkS")
		)
		(fp_line
			(start 0.67945 0.3048)
			(end 0.120396 0.3048)
			(stroke
				(width 0.1)
				(type default)
			)
			(layer "F.Fab")
		)
		(fp_line
			(start 0.67945 -0.3048)
			(end 0.67945 0.3048)
			(stroke
				(width 0.1)
				(type default)
			)
			(layer "F.Fab")
		)
		(fp_line
			(start 0.12065 -0.2794)
			(end 0.12065 -0.3048)
			(stroke
				(width 0.1)
				(type default)
			)
			(layer "F.Fab")
		)
		(fp_line
			(start 0.12065 -0.3048)
			(end 0.67945 -0.3048)
			(stroke
				(width 0.1)
				(type default)
			)
			(layer "F.Fab")
		)
		(fp_line
			(start 0.120396 0.3048)
			(end 0.120396 0.2794)
			(stroke
				(width 0.1)
				(type default)
			)
			(layer "F.Fab")
		)
		(fp_line
			(start 0.120396 0.2794)
			(end -0.12065 0.2794)
			(stroke
				(width 0.1)
				(type default)
			)
			(layer "F.Fab")
		)
		(fp_line
			(start -0.12065 0.3048)
			(end -0.67945 0.3048)
			(stroke
				(width 0.1)
				(type default)
			)
			(layer "F.Fab")
		)
		(fp_line
			(start -0.12065 0.2794)
			(end -0.12065 0.3048)
			(stroke
				(width 0.1)
				(type default)
			)
			(layer "F.Fab")
		)
		(fp_line
			(start -0.12065 -0.2794)
			(end 0.12065 -0.2794)
			(stroke
				(width 0.1)
				(type default)
			)
			(layer "F.Fab")
		)
		(fp_line
			(start -0.12065 -0.305054)
			(end -0.12065 -0.2794)
			(stroke
				(width 0.1)
				(type default)
			)
			(layer "F.Fab")
		)
		(fp_line
			(start -0.67945 0.3048)
			(end -0.67945 -0.305054)
			(stroke
				(width 0.1)
				(type default)
			)
			(layer "F.Fab")
		)
		(fp_line
			(start -0.67945 -0.305054)
			(end -0.12065 -0.305054)
			(stroke
				(width 0.1)
				(type default)
			)
			(layer "F.Fab")
		)
		(pad "1" smd circle
			(at -0.40005 0 180)
			(size 0 0)
			(layers "F.Cu" "F.Mask" "F.Paste")
			(net "NCSI_BMC_RXD1_R")
		)
		(pad "2" smd circle
			(at 0.40005 0 180)
			(size 0 0)
			(layers "F.Cu" "F.Mask" "F.Paste")
			(net "RMII_OCP_BMC_RXD_1")
		)
	)
	(footprint ""
		(layer "F.Cu")
		(at 118.5164 -36.67125 90)
		(property "Reference" "R6270"
			(at 0 0 90)
			(layer "F.SilkS")
			(hide yes)
			(effects
				(font
					(size 1.27 1.27)
				)
			)
		)
		(property "Value" ""
			(at 0 0 90)
			(layer "F.Fab")
			(effects
				(font
					(size 1.27 1.27)
				)
			)
		)
		(duplicate_pad_numbers_are_jumpers no)
		(fp_line
			(start 0.7874 -0.4064)
			(end 0.7874 0.4064)
			(stroke
				(width 0.1524)
				(type default)
			)
			(layer "F.SilkS")
		)
		(fp_line
			(start -0.7874 -0.4064)
			(end 0.7874 -0.4064)
			(stroke
				(width 0.1524)
				(type default)
			)
			(layer "F.SilkS")
		)
		(fp_line
			(start 0.7874 0.4064)
			(end -0.7874 0.4064)
			(stroke
				(width 0.1524)
				(type default)
			)
			(layer "F.SilkS")
		)
		(fp_line
			(start -0.7874 0.4064)
			(end -0.7874 -0.4064)
			(stroke
				(width 0.1524)
				(type default)
			)
			(layer "F.SilkS")
		)
		(fp_line
			(start -0.12065 -0.305054)
			(end -0.12065 -0.2794)
			(stroke
				(width 0.1)
				(type default)
			)
			(layer "F.Fab")
		)
		(fp_line
			(start -0.67945 -0.305054)
			(end -0.12065 -0.305054)
			(stroke
				(width 0.1)
				(type default)
			)
			(layer "F.Fab")
		)
		(fp_line
			(start 0.67945 -0.3048)
			(end 0.67945 0.3048)
			(stroke
				(width 0.1)
				(type default)
			)
			(layer "F.Fab")
		)
		(fp_line
			(start 0.12065 -0.3048)
			(end 0.67945 -0.3048)
			(stroke
				(width 0.1)
				(type default)
			)
			(layer "F.Fab")
		)
		(fp_line
			(start 0.12065 -0.2794)
			(end 0.12065 -0.3048)
			(stroke
				(width 0.1)
				(type default)
			)
			(layer "F.Fab")
		)
		(fp_line
			(start -0.12065 -0.2794)
			(end 0.12065 -0.2794)
			(stroke
				(width 0.1)
				(type default)
			)
			(layer "F.Fab")
		)
		(fp_line
			(start 0.120396 0.2794)
			(end -0.12065 0.2794)
			(stroke
				(width 0.1)
				(type default)
			)
			(layer "F.Fab")
		)
		(fp_line
			(start -0.12065 0.2794)
			(end -0.12065 0.3048)
			(stroke
				(width 0.1)
				(type default)
			)
			(layer "F.Fab")
		)
		(fp_line
			(start 0.67945 0.3048)
			(end 0.120396 0.3048)
			(stroke
				(width 0.1)
				(type default)
			)
			(layer "F.Fab")
		)
		(fp_line
			(start 0.120396 0.3048)
			(end 0.120396 0.2794)
			(stroke
				(width 0.1)
				(type default)
			)
			(layer "F.Fab")
		)
		(fp_line
			(start -0.12065 0.3048)
			(end -0.67945 0.3048)
			(stroke
				(width 0.1)
				(type default)
			)
			(layer "F.Fab")
		)
		(fp_line
			(start -0.67945 0.3048)
			(end -0.67945 -0.305054)
			(stroke
				(width 0.1)
				(type default)
			)
			(layer "F.Fab")
		)
		(pad "1" smd circle
			(at -0.40005 0 90)
			(size 0 0)
			(layers "F.Cu" "F.Mask" "F.Paste")
			(net "P3V3_AUX_CPU0_USB2_AVDD33")
		)
		(pad "2" smd circle
			(at 0.40005 0 90)
			(size 0 0)
			(layers "F.Cu" "F.Mask" "F.Paste")
			(net "USB_HUB2_TI_PWRCTL3_MRP_VDD33")
		)
	)
	(footprint ""
		(layer "F.Cu")
		(at 19.844258 -427.580298 90)
		(property "Reference" "R6164"
			(at 0 0 90)
			(layer "F.SilkS")
			(hide yes)
			(effects
				(font
					(size 1.27 1.27)
				)
			)
		)
		(property "Value" ""
			(at 0 0 90)
			(layer "F.Fab")
			(effects
				(font
					(size 1.27 1.27)
				)
			)
		)
		(duplicate_pad_numbers_are_jumpers no)
		(fp_line
			(start 0.7874 -0.4064)
			(end 0.7874 0.4064)
			(stroke
				(width 0.1524)
				(type default)
			)
			(layer "F.SilkS")
		)
		(fp_line
			(start -0.7874 -0.4064)
			(end 0.7874 -0.4064)
			(stroke
				(width 0.1524)
				(type default)
			)
			(layer "F.SilkS")
		)
		(fp_line
			(start 0.7874 0.4064)
			(end -0.7874 0.4064)
			(stroke
				(width 0.1524)
				(type default)
			)
			(layer "F.SilkS")
		)
		(fp_line
			(start -0.7874 0.4064)
			(end -0.7874 -0.4064)
			(stroke
				(width 0.1524)
				(type default)
			)
			(layer "F.SilkS")
		)
		(fp_line
			(start -0.12065 -0.305054)
			(end -0.12065 -0.2794)
			(stroke
				(width 0.1)
				(type default)
			)
			(layer "F.Fab")
		)
		(fp_line
			(start -0.67945 -0.305054)
			(end -0.12065 -0.305054)
			(stroke
				(width 0.1)
				(type default)
			)
			(layer "F.Fab")
		)
		(fp_line
			(start 0.67945 -0.3048)
			(end 0.67945 0.3048)
			(stroke
				(width 0.1)
				(type default)
			)
			(layer "F.Fab")
		)
		(fp_line
			(start 0.12065 -0.3048)
			(end 0.67945 -0.3048)
			(stroke
				(width 0.1)
				(type default)
			)
			(layer "F.Fab")
		)
		(fp_line
			(start 0.12065 -0.2794)
			(end 0.12065 -0.3048)
			(stroke
				(width 0.1)
				(type default)
			)
			(layer "F.Fab")
		)
		(fp_line
			(start -0.12065 -0.2794)
			(end 0.12065 -0.2794)
			(stroke
				(width 0.1)
				(type default)
			)
			(layer "F.Fab")
		)
		(fp_line
			(start 0.120396 0.2794)
			(end -0.12065 0.2794)
			(stroke
				(width 0.1)
				(type default)
			)
			(layer "F.Fab")
		)
		(fp_line
			(start -0.12065 0.2794)
			(end -0.12065 0.3048)
			(stroke
				(width 0.1)
				(type default)
			)
			(layer "F.Fab")
		)
		(fp_line
			(start 0.67945 0.3048)
			(end 0.120396 0.3048)
			(stroke
				(width 0.1)
				(type default)
			)
			(layer "F.Fab")
		)
		(fp_line
			(start 0.120396 0.3048)
			(end 0.120396 0.2794)
			(stroke
				(width 0.1)
				(type default)
			)
			(layer "F.Fab")
		)
		(fp_line
			(start -0.12065 0.3048)
			(end -0.67945 0.3048)
			(stroke
				(width 0.1)
				(type default)
			)
			(layer "F.Fab")
		)
		(fp_line
			(start -0.67945 0.3048)
			(end -0.67945 -0.305054)
			(stroke
				(width 0.1)
				(type default)
			)
			(layer "F.Fab")
		)
		(pad "1" smd circle
			(at -0.40005 0 90)
			(size 0 0)
			(layers "F.Cu" "F.Mask" "F.Paste")
			(net "FM_P2E_BUF2_EQB1")
		)
		(pad "2" smd circle
			(at 0.40005 0 90)
			(size 0 0)
			(layers "F.Cu" "F.Mask" "F.Paste")
			(net "GND")
		)
	)
	(footprint ""
		(layer "F.Cu")
		(at 288.314384 -343.712038 180)
		(property "Reference" "PC159"
			(at 0 0 180)
			(layer "F.SilkS")
			(hide yes)
			(effects
				(font
					(size 1.27 1.27)
				)
			)
		)
		(property "Value" ""
			(at 0 0 180)
			(layer "F.Fab")
			(effects
				(font
					(size 1.27 1.27)
				)
			)
		)
		(duplicate_pad_numbers_are_jumpers no)
		(fp_line
			(start 0.7874 0.4064)
			(end -0.7874 0.4064)
			(stroke
				(width 0.1524)
				(type default)
			)
			(layer "F.SilkS")
		)
		(fp_line
			(start 0.7874 -0.4064)
			(end 0.7874 0.4064)
			(stroke
				(width 0.1524)
				(type default)
			)
			(layer "F.SilkS")
		)
		(fp_line
			(start -0.7874 0.4064)
			(end -0.7874 -0.4064)
			(stroke
				(width 0.1524)
				(type default)
			)
			(layer "F.SilkS")
		)
		(fp_line
			(start -0.7874 -0.4064)
			(end 0.7874 -0.4064)
			(stroke
				(width 0.1524)
				(type default)
			)
			(layer "F.SilkS")
		)
		(fp_line
			(start 0.67945 0.3048)
			(end 0.120396 0.3048)
			(stroke
				(width 0.1)
				(type default)
			)
			(layer "F.Fab")
		)
		(fp_line
			(start 0.67945 -0.3048)
			(end 0.67945 0.3048)
			(stroke
				(width 0.1)
				(type default)
			)
			(layer "F.Fab")
		)
		(fp_line
			(start 0.12065 -0.2794)
			(end 0.12065 -0.3048)
			(stroke
				(width 0.1)
				(type default)
			)
			(layer "F.Fab")
		)
		(fp_line
			(start 0.12065 -0.3048)
			(end 0.67945 -0.3048)
			(stroke
				(width 0.1)
				(type default)
			)
			(layer "F.Fab")
		)
		(fp_line
			(start 0.120396 0.3048)
			(end 0.120396 0.2794)
			(stroke
				(width 0.1)
				(type default)
			)
			(layer "F.Fab")
		)
		(fp_line
			(start 0.120396 0.2794)
			(end -0.12065 0.2794)
			(stroke
				(width 0.1)
				(type default)
			)
			(layer "F.Fab")
		)
		(fp_line
			(start -0.12065 0.3048)
			(end -0.67945 0.3048)
			(stroke
				(width 0.1)
				(type default)
			)
			(layer "F.Fab")
		)
		(fp_line
			(start -0.12065 0.2794)
			(end -0.12065 0.3048)
			(stroke
				(width 0.1)
				(type default)
			)
			(layer "F.Fab")
		)
		(fp_line
			(start -0.12065 -0.2794)
			(end 0.12065 -0.2794)
			(stroke
				(width 0.1)
				(type default)
			)
			(layer "F.Fab")
		)
		(fp_line
			(start -0.12065 -0.305054)
			(end -0.12065 -0.2794)
			(stroke
				(width 0.1)
				(type default)
			)
			(layer "F.Fab")
		)
		(fp_line
			(start -0.67945 0.3048)
			(end -0.67945 -0.305054)
			(stroke
				(width 0.1)
				(type default)
			)
			(layer "F.Fab")
		)
		(fp_line
			(start -0.67945 -0.305054)
			(end -0.12065 -0.305054)
			(stroke
				(width 0.1)
				(type default)
			)
			(layer "F.Fab")
		)
		(pad "1" smd circle
			(at -0.40005 0 180)
			(size 0 0)
			(layers "F.Cu" "F.Mask" "F.Paste")
			(net "SW_PVDDIO_P0_SW2")
		)
		(pad "2" smd circle
			(at 0.40005 0 180)
			(size 0 0)
			(layers "F.Cu" "F.Mask" "F.Paste")
			(net "SW_PVDDIO_P0_SW2_RC")
		)
	)
)
